# BASEBOARD_FAB2 (Tioga Pass) — schematic netlist excerpt (pin names and nets, part order shuffled) for the footprints in the layout excerpt that follows; sources: Cadence DE-HDL packaged netlist, KiCad conversion of Wiwynn_Tioga_Pass_MB.brd

J2W1  SKT-SATA7P-6P-165-GP-U1  pkg SOCKET-G6  page 172
  H1  = GND
  H2  = GND
  NP1  = NC
  NP2  = NC
  P1  = P5V_HDD_SATA
  P2  = P5V_HDD_SATA
  P3  = GND
  P4  = GND
  P5  = P12V_HDD_SATA
  P6  = P12V_HDD_SATA
  S1  = GND
  S2  = SATA6G_S1_TX_C_DP
  S3  = SATA6G_S1_TX_C_DN
  S4  = GND
  S5  = SATA6G_S1_RX_C_DN
  S6  = SATA6G_S1_RX_C_DP
  S7  = GND

(kicad_pcb
	(version 20260206)
	(generator "pcbnew")
	(generator_version "10.0")
	(general
		(thickness 1.6)
		(legacy_teardrops no)
	)
	(paper "A4")
	(title_block
		(title "Wiwynn_Tioga_Pass_MB.brd")
		(comment 1 "Tioga Pass / footprint 4562 of 4770 (J2W1), pads 1-17 of 17")
	)
	(layers
		(0 "F.Cu" signal "TOP")
		(4 "In1.Cu" signal "L2GND")
		(6 "In2.Cu" signal "L3")
		(8 "In3.Cu" signal "L4GND")
		(10 "In4.Cu" signal "L5")
		(12 "In5.Cu" signal "L6GND")
		(14 "In6.Cu" signal "L7VCC")
		(16 "In7.Cu" signal "L8VCC")
		(18 "In8.Cu" signal "L9GND")
		(20 "In9.Cu" signal "L10")
		(22 "In10.Cu" signal "L11GND")
		(24 "In11.Cu" signal "L12")
		(26 "In12.Cu" signal "L13GND")
		(2 "B.Cu" signal "BOTTOM")
		(9 "F.Adhes" user "F.Adhesive")
		(11 "B.Adhes" user "B.Adhesive")
		(13 "F.Paste" user "Package Geometry/Pastemask Top")
		(15 "B.Paste" user "Package Geometry/Pastemask Bottom")
		(5 "F.SilkS" user "Ref Des/Silkscreen Top")
		(7 "B.SilkS" user "Ref Des/Silkscreen Bottom")
		(1 "F.Mask" user "Board Geometry/Soldermask Top")
		(3 "B.Mask" user "Board Geometry/Soldermask Bottom")
		(17 "Dwgs.User" user "User.Drawings")
		(19 "Cmts.User" user "User.Comments")
		(21 "Eco1.User" user "User.Eco1")
		(23 "Eco2.User" user "User.Eco2")
		(25 "Edge.Cuts" user "Board Geometry/Outline")
		(27 "Margin" user)
		(31 "F.CrtYd" user "Package Geometry/Place Bound Top")
		(29 "B.CrtYd" user "Package Geometry/Place Bound Bottom")
		(35 "F.Fab" user "Ref Des/Assembly Top")
		(33 "B.Fab" user "Ref Des/Assembly Bottom")
	)
	(footprint ""
		(layer "B.Cu")
		(at 437.930036 -137.044938)
		(property "Reference" "J2W1"
			(at 0 0 0)
			(layer "B.SilkS")
			(hide yes)
			(effects
				(font
					(size 1.27 1.27)
				)
				(justify mirror)
			)
		)
		(property "Value" "*"
			(at 2.3622 -8.3185 0)
			(unlocked yes)
			(layer "B.Fab")
			(hide yes)
			(effects
				(font
					(size 1.27 1.016)
					(thickness 0.1524)
				)
				(justify mirror)
			)
		)
		(property "Device Type" "SKT-SATA7P-6P-165-GP-U1_SOCKETA"
			(at 2.3622 -9.8425 0)
			(unlocked yes)
			(layer "B.Fab")
			(hide yes)
			(effects
				(font
					(size 1.27 1.016)
					(thickness 0.1524)
				)
				(justify mirror)
			)
		)
		(duplicate_pad_numbers_are_jumpers no)
		(pad "" np_thru_hole circle
			(at -12.500102 -1.400048 180)
			(size 0.254 0.254)
			(drill 1.651)
			(layers "*.Cu" "*.Mask")
			(clearance 1.0541)
			(thermal_gap 1.0541)
		)
		(pad "" np_thru_hole circle
			(at 12.500102 -1.400048 180)
			(size 0.254 0.254)
			(drill 1.651)
			(layers "*.Cu" "*.Mask")
			(clearance 1.0541)
			(thermal_gap 1.0541)
		)
		(pad "H1" smd rect
			(at -16.249904 0 180)
			(size 2.5908 3.683)
			(layers "B.Cu" "B.Mask" "B.Paste")
			(net "GND")
		)
		(pad "H2" smd rect
			(at 16.249904 0 180)
			(size 2.5908 3.683)
			(layers "B.Cu" "B.Mask" "B.Paste")
			(net "GND")
		)
		(pad "P1" thru_hole oval
			(at 4.45008 0.700024 180)
			(size 0.8128 0.9144)
			(drill 0.5588)
			(layers "*.Cu" "*.Mask")
			(remove_unused_layers no)
			(net "P5V_HDD_SATA")
			(clearance 0.2286)
			(thermal_gap 0.2286)
		)
		(pad "P2" thru_hole oval
			(at 5.450078 0.700024 180)
			(size 0.8128 0.9144)
			(drill 0.5588)
			(layers "*.Cu" "*.Mask")
			(remove_unused_layers no)
			(net "P5V_HDD_SATA")
			(clearance 0.2286)
			(thermal_gap 0.2286)
		)
		(pad "P3" thru_hole oval
			(at 6.450076 0.700024 180)
			(size 0.8128 0.9144)
			(drill 0.5588)
			(layers "*.Cu" "*.Mask")
			(remove_unused_layers no)
			(net "GND")
			(clearance 0.2286)
			(thermal_gap 0.2286)
		)
		(pad "P4" thru_hole oval
			(at 7.450074 0.700024 180)
			(size 0.8128 0.9144)
			(drill 0.5588)
			(layers "*.Cu" "*.Mask")
			(remove_unused_layers no)
			(net "GND")
			(clearance 0.2286)
			(thermal_gap 0.2286)
		)
		(pad "P5" thru_hole oval
			(at 8.450072 0.700024 180)
			(size 0.8128 0.9144)
			(drill 0.5588)
			(layers "*.Cu" "*.Mask")
			(remove_unused_layers no)
			(net "P12V_HDD_SATA")
			(clearance 0.2286)
			(thermal_gap 0.2286)
		)
		(pad "P6" thru_hole oval
			(at 9.45007 0.700024 180)
			(size 0.8128 0.9144)
			(drill 0.5588)
			(layers "*.Cu" "*.Mask")
			(remove_unused_layers no)
			(net "P12V_HDD_SATA")
			(clearance 0.2286)
			(thermal_gap 0.2286)
		)
		(pad "S1" thru_hole circle
			(at -9.379966 0.700024 180)
			(size 1.016 1.016)
			(drill 0.6604)
			(layers "*.Cu" "*.Mask")
			(remove_unused_layers no)
			(net "GND")
			(clearance 0.1778)
			(thermal_gap 0.1778)
		)
		(pad "S2" thru_hole circle
			(at -8.109966 0.700024 180)
			(size 1.016 1.016)
			(drill 0.6604)
			(layers "*.Cu" "*.Mask")
			(remove_unused_layers no)
			(net "SATA6G_S1_TX_C_DP")
			(clearance 0.1778)
			(thermal_gap 0.1778)
		)
		(pad "S3" thru_hole circle
			(at -6.839966 0.700024 180)
			(size 1.016 1.016)
			(drill 0.6604)
			(layers "*.Cu" "*.Mask")
			(remove_unused_layers no)
			(net "SATA6G_S1_TX_C_DN")
			(clearance 0.1778)
			(thermal_gap 0.1778)
		)
		(pad "S4" thru_hole circle
			(at -5.569966 0.700024 180)
			(size 1.016 1.016)
			(drill 0.6604)
			(layers "*.Cu" "*.Mask")
			(remove_unused_layers no)
			(net "GND")
			(clearance 0.1778)
			(thermal_gap 0.1778)
		)
		(pad "S5" thru_hole circle
			(at -4.299966 0.700024 180)
			(size 1.016 1.016)
			(drill 0.6604)
			(layers "*.Cu" "*.Mask")
			(remove_unused_layers no)
			(net "SATA6G_S1_RX_C_DN")
			(clearance 0.1778)
			(thermal_gap 0.1778)
		)
		(pad "S6" thru_hole circle
			(at -3.029966 0.700024 180)
			(size 1.016 1.016)
			(drill 0.6604)
			(layers "*.Cu" "*.Mask")
			(remove_unused_layers no)
			(net "SATA6G_S1_RX_C_DP")
			(clearance 0.1778)
			(thermal_gap 0.1778)
		)
		(pad "S7" thru_hole circle
			(at -1.759966 0.700024 180)
			(size 1.016 1.016)
			(drill 0.6604)
			(layers "*.Cu" "*.Mask")
			(remove_unused_layers no)
			(net "GND")
			(clearance 0.1778)
			(thermal_gap 0.1778)
		)
	)
)
